FILE_TYPE = CONNECTIVITY;
{Allegro Design Entry HDL 17.2-2016 S081 (4005846) 1/11/2022}
"PAGE_NUMBER" = 118;
0"NC";
1"PVNN_TERM_CPU1\g";
2"PVNN_TERM_CPU0\g";
3"PVNN_TERM_CPU1\g";
4"PVNN_TERM_CPU0\g";
5"H_CPU0_CATERR_LVC1_R_N";
6"PWRGD_CPUPWRGD_GTL";
7"PWRGD_CPUPWRGD_LVC1_R";
8"H_CPU1_RMCA_LVC1_R_N";
9"H_CPU_RMCA_LVC1_R_N";
10"H_CPU0_RMCA_LVC1_R_N";
11"H_CPU_CATERR_LVC1_R_N";
12"H_CPU1_CATERR_LVC1_R_N";
%"Q_RES"
"1","(-1400,-225)","0","pure_quanta","I101";
;
PART_NUMBER"CS00002JB13"
MATERIAL"CHIP"
VALUE"0"
TOLERANCE"5%"
PACK_TYPE"0402LF"
WATTAGE"1/16W"
LOCATION"R302"
CDS_LIB"pure_quanta"
$SEC"1"
CDS_SEC"1";
"B"
$PN"2"9;
"A"
$PN"1"10;
%"Q_RES"
"1","(-1400,-700)","0","pure_quanta","I102";
;
PART_NUMBER"CS00002JB13"
MATERIAL"CHIP"
PACK_TYPE"0402LF"
VALUE"0"
TOLERANCE"5%"
WATTAGE"1/16W"
LOCATION"R304"
CDS_LIB"pure_quanta"
$SEC"1"
CDS_SEC"1";
"B"
$PN"2"9;
"A"
$PN"1"8;
%"Q_RES"
"1","(-1400,1050)","0","pure_quanta","I23";
;
PART_NUMBER"CS00002JB13"
MATERIAL"CHIP"
TOLERANCE"5%"
VALUE"0"
WATTAGE"1/16W"
PACK_TYPE"0402LF"
$LOCATION"R297"
CDS_LIB"pure_quanta"
CDS_LOCATION"R297"
$SEC"1"
CDS_SEC"1";
"B"
$PN"2"11;
"A"
$PN"1"5;
%"Q_RES"
"1","(-1400,575)","0","pure_quanta","I63";
;
PART_NUMBER"CS00002JB13"
PACK_TYPE"0402LF"
VALUE"0"
MATERIAL"CHIP"
WATTAGE"1/16W"
TOLERANCE"5%"
$LOCATION"R299"
CDS_LIB"pure_quanta"
CDS_LOCATION"R299"
$SEC"1"
CDS_SEC"1";
"B"
$PN"2"11;
"A"
$PN"1"12;
%"Q_RES"
"1","(-1400,1250)","0","pure_quanta","I65";
;
PART_NUMBER"CS13012FB02"
WATTAGE"1/16W"
TOLERANCE"1%"
PACK_TYPE"0402LF"
VALUE"301"
MATERIAL"CHIP"
$LOCATION"R296"
CDS_LIB"pure_quanta"
CDS_LOCATION"R296"
$SEC"1"
CDS_SEC"1";
"B"
$PN"2"11;
"A"
$PN"1"4;
%"UNIVERSAL_POWER"
"1","(-1950,1350)","0","logical_power","I66";
;
HDL_POWER"PVNN_TERM_CPU0"
CDS_LIB"logical_power";
"A"4;
%"Q_RES"
"1","(-1400,775)","0","pure_quanta","I67";
;
PART_NUMBER"CS13012FB02"
VALUE"301"
MATERIAL"CHIP"
TOLERANCE"1%"
WATTAGE"1/16W"
PACK_TYPE"0402LF"
$LOCATION"R298"
CDS_LIB"pure_quanta"
CDS_LOCATION"R298"
$SEC"1"
CDS_SEC"1";
"B"
$PN"2"11;
"A"
$PN"1"3;
%"UNIVERSAL_POWER"
"1","(-1950,875)","0","logical_power","I68";
;
HDL_POWER"PVNN_TERM_CPU1"
CDS_LIB"logical_power";
"A"3;
%"Q_RES"
"1","(-1400,-25)","0","pure_quanta","I73";
;
PART_NUMBER"CS13012FB02"
TOLERANCE"1%"
MATERIAL"CHIP"
WATTAGE"1/16W"
PACK_TYPE"0402LF"
VALUE"301"
$LOCATION"R301"
CDS_LIB"pure_quanta"
CDS_LOCATION"R301"
$SEC"1"
CDS_SEC"1";
"B"
$PN"2"9;
"A"
$PN"1"2;
%"UNIVERSAL_POWER"
"1","(-1950,75)","0","logical_power","I74";
;
HDL_POWER"PVNN_TERM_CPU0"
CDS_LIB"logical_power";
"A"2;
%"Q_RES"
"1","(-1400,-500)","0","pure_quanta","I76";
;
PART_NUMBER"CS13012FB02"
MATERIAL"CHIP"
WATTAGE"1/16W"
VALUE"301"
PACK_TYPE"0402LF"
TOLERANCE"1%"
$LOCATION"R303"
CDS_LIB"pure_quanta"
CDS_LOCATION"R303"
$SEC"1"
CDS_SEC"1";
"B"
$PN"2"9;
"A"
$PN"1"1;
%"UNIVERSAL_POWER"
"1","(-1950,-400)","0","logical_power","I78";
;
HDL_POWER"PVNN_TERM_CPU1"
CDS_LIB"logical_power";
"A"1;
%"Q_RES"
"1","(-775,-1400)","0","pure_quanta","I92";
;
PART_NUMBER"CS03322FB03"
MATERIAL"CHIP"
WATTAGE"1/16W"
PACK_TYPE"0402LF"
TOLERANCE"1%"
VALUE"33.2"
$LOCATION"R315"
CDS_LIB"pure_quanta"
CDS_LOCATION"R315"
$SEC"1"
CDS_SEC"1";
"B"
$PN"2"7;
"A"
$PN"1"6;
END.
